(kicad_pcb
	(version 20260206)
	(generator "pcbnew")
	(generator_version "10.0")
	(general
		(thickness 1.6)
		(legacy_teardrops no)
	)
	(paper "A4")
	(title_block
		(title "01162023_DA0F0TEBIF0_F0T_Expander_BD_F_brd_V02_OCP.brd")
		(comment 1 "Grand Teton / footprints 3520-3525 of 9728")
	)
	(layers
		(0 "F.Cu" signal "TOP")
		(4 "In1.Cu" signal "GND")
		(6 "In2.Cu" signal "VCC")
		(8 "In3.Cu" signal "VCC1")
		(10 "In4.Cu" signal "GND1")
		(12 "In5.Cu" signal "IN1")
		(14 "In6.Cu" signal "GND2")
		(16 "In7.Cu" signal "IN2")
		(18 "In8.Cu" signal "GND3")
		(20 "In9.Cu" signal "IN3")
		(22 "In10.Cu" signal "GND4")
		(24 "In11.Cu" signal "IN4")
		(26 "In12.Cu" signal "GND5")
		(28 "In13.Cu" signal "IN5")
		(30 "In14.Cu" signal "GND6")
		(32 "In15.Cu" signal "IN6")
		(34 "In16.Cu" signal "GND7")
		(2 "B.Cu" signal "BOTTOM")
		(9 "F.Adhes" user "F.Adhesive")
		(11 "B.Adhes" user "B.Adhesive")
		(13 "F.Paste" user "Package Geometry/Pastemask Top")
		(15 "B.Paste" user "Package Geometry/Pastemask Bottom")
		(5 "F.SilkS" user "Ref Des/Silkscreen Top")
		(7 "B.SilkS" user "Ref Des/Silkscreen Bottom")
		(1 "F.Mask" user "Board Geometry/Soldermask Top")
		(3 "B.Mask" user "Board Geometry/Soldermask Bottom")
		(17 "Dwgs.User" user "User.Drawings")
		(19 "Cmts.User" user "User.Comments")
		(21 "Eco1.User" user "User.Eco1")
		(23 "Eco2.User" user "User.Eco2")
		(25 "Edge.Cuts" user "Board Geometry/Outline")
		(27 "Margin" user)
		(31 "F.CrtYd" user "Package Geometry/Place Bound Top")
		(29 "B.CrtYd" user "Package Geometry/Place Bound Bottom")
		(35 "F.Fab" user "Ref Des/Assembly Top")
		(33 "B.Fab" user "Ref Des/Assembly Bottom")
	)
	(footprint ""
		(layer "F.Cu")
		(at 360.607356 -238.580168 180)
		(property "Reference" "R6407"
			(at 0 0 180)
			(layer "F.SilkS")
			(hide yes)
			(effects
				(font
					(size 1.27 1.27)
				)
			)
		)
		(property "Value" ""
			(at 0 0 180)
			(layer "F.Fab")
			(effects
				(font
					(size 1.27 1.27)
				)
			)
		)
		(duplicate_pad_numbers_are_jumpers no)
		(fp_line
			(start 0.7874 0.4064)
			(end -0.7874 0.4064)
			(stroke
				(width 0.1524)
				(type default)
			)
			(layer "F.SilkS")
		)
		(fp_line
			(start 0.7874 -0.4064)
			(end 0.7874 0.4064)
			(stroke
				(width 0.1524)
				(type default)
			)
			(layer "F.SilkS")
		)
		(fp_line
			(start -0.7874 0.4064)
			(end -0.7874 -0.4064)
			(stroke
				(width 0.1524)
				(type default)
			)
			(layer "F.SilkS")
		)
		(fp_line
			(start -0.7874 -0.4064)
			(end 0.7874 -0.4064)
			(stroke
				(width 0.1524)
				(type default)
			)
			(layer "F.SilkS")
		)
		(fp_line
			(start 0.67945 0.3048)
			(end 0.120396 0.3048)
			(stroke
				(width 0.1)
				(type default)
			)
			(layer "F.Fab")
		)
		(fp_line
			(start 0.67945 -0.3048)
			(end 0.67945 0.3048)
			(stroke
				(width 0.1)
				(type default)
			)
			(layer "F.Fab")
		)
		(fp_line
			(start 0.12065 -0.2794)
			(end 0.12065 -0.3048)
			(stroke
				(width 0.1)
				(type default)
			)
			(layer "F.Fab")
		)
		(fp_line
			(start 0.12065 -0.3048)
			(end 0.67945 -0.3048)
			(stroke
				(width 0.1)
				(type default)
			)
			(layer "F.Fab")
		)
		(fp_line
			(start 0.120396 0.3048)
			(end 0.120396 0.2794)
			(stroke
				(width 0.1)
				(type default)
			)
			(layer "F.Fab")
		)
		(fp_line
			(start 0.120396 0.2794)
			(end -0.12065 0.2794)
			(stroke
				(width 0.1)
				(type default)
			)
			(layer "F.Fab")
		)
		(fp_line
			(start -0.12065 0.3048)
			(end -0.67945 0.3048)
			(stroke
				(width 0.1)
				(type default)
			)
			(layer "F.Fab")
		)
		(fp_line
			(start -0.12065 0.2794)
			(end -0.12065 0.3048)
			(stroke
				(width 0.1)
				(type default)
			)
			(layer "F.Fab")
		)
		(fp_line
			(start -0.12065 -0.2794)
			(end 0.12065 -0.2794)
			(stroke
				(width 0.1)
				(type default)
			)
			(layer "F.Fab")
		)
		(fp_line
			(start -0.12065 -0.305054)
			(end -0.12065 -0.2794)
			(stroke
				(width 0.1)
				(type default)
			)
			(layer "F.Fab")
		)
		(fp_line
			(start -0.67945 0.3048)
			(end -0.67945 -0.305054)
			(stroke
				(width 0.1)
				(type default)
			)
			(layer "F.Fab")
		)
		(fp_line
			(start -0.67945 -0.305054)
			(end -0.12065 -0.305054)
			(stroke
				(width 0.1)
				(type default)
			)
			(layer "F.Fab")
		)
		(pad "1" smd circle
			(at -0.40005 0 180)
			(size 0 0)
			(layers "F.Cu" "F.Mask" "F.Paste")
			(net "PWRGD_P5V_AUX_R2")
		)
		(pad "2" smd circle
			(at 0.40005 0 180)
			(size 0 0)
			(layers "F.Cu" "F.Mask" "F.Paste")
			(net "PWRGD_P5V_AUX_R")
		)
	)
	(footprint ""
		(layer "F.Cu")
		(at 83.589368 -63.56223)
		(property "Reference" "Q130"
			(at -0.224028 -2.570734 0)
			(unlocked yes)
			(layer "F.SilkS")
			(effects
				(font
					(size 0.7874 0.5842)
					(thickness 0.1524)
				)
			)
		)
		(property "Value" ""
			(at 0 0 0)
			(layer "F.Fab")
			(effects
				(font
					(size 1.27 1.27)
				)
			)
		)
		(duplicate_pad_numbers_are_jumpers no)
		(fp_line
			(start -1.376172 -1.199896)
			(end -0.508 -1.199896)
			(stroke
				(width 0.1524)
				(type default)
			)
			(layer "F.SilkS")
		)
		(fp_line
			(start -1.376172 1.199896)
			(end -1.376172 -1.199896)
			(stroke
				(width 0.1524)
				(type default)
			)
			(layer "F.SilkS")
		)
		(fp_line
			(start -0.508 -1.199896)
			(end 0 -0.762)
			(stroke
				(width 0.1524)
				(type default)
			)
			(layer "F.SilkS")
		)
		(fp_line
			(start 0 -0.762)
			(end 0.508 -1.199896)
			(stroke
				(width 0.1524)
				(type default)
			)
			(layer "F.SilkS")
		)
		(fp_line
			(start 0.508 -1.199896)
			(end 1.376172 -1.199896)
			(stroke
				(width 0.1524)
				(type default)
			)
			(layer "F.SilkS")
		)
		(fp_line
			(start 1.376172 -1.199896)
			(end 1.376172 1.199896)
			(stroke
				(width 0.1524)
				(type default)
			)
			(layer "F.SilkS")
		)
		(fp_line
			(start 1.376172 1.199896)
			(end -1.376172 1.199896)
			(stroke
				(width 0.1524)
				(type default)
			)
			(layer "F.SilkS")
		)
		(fp_poly
			(pts
				(xy -1.586738 -0.940308) (xy -1.856232 -1.748536) (xy -2.394966 -1.209802)
			)
			(stroke
				(width 0)
				(type default)
			)
			(fill yes)
			(layer "F.SilkS")
		)
		(fp_line
			(start -0.674878 -1.100074)
			(end 0.674878 -1.100074)
			(stroke
				(width 0.1)
				(type default)
			)
			(layer "F.Fab")
		)
		(fp_line
			(start -0.674878 1.100074)
			(end -0.674878 -1.100074)
			(stroke
				(width 0.1)
				(type default)
			)
			(layer "F.Fab")
		)
		(fp_line
			(start 0.674878 -1.100074)
			(end 0.674878 1.100074)
			(stroke
				(width 0.1)
				(type default)
			)
			(layer "F.Fab")
		)
		(fp_line
			(start 0.674878 1.100074)
			(end -0.674878 1.100074)
			(stroke
				(width 0.1)
				(type default)
			)
			(layer "F.Fab")
		)
		(fp_poly
			(pts
				(xy -1.4605 -0.7493) (xy -2.2225 -1.1303) (xy -2.2225 -0.3683)
			)
			(stroke
				(width 0)
				(type default)
			)
			(fill yes)
			(layer "F.Fab")
		)
		(pad "1" smd rect
			(at -0.899922 -0.750062 270)
			(size 0.6096 0.6096)
			(layers "F.Cu" "F.Mask" "F.Paste")
			(net "GND")
		)
		(pad "2" smd rect
			(at -0.899922 0 270)
			(size 0.4064 0.6096)
			(layers "F.Cu" "F.Mask" "F.Paste")
			(net "P12V_SSD3_PG_G1")
		)
		(pad "3" smd rect
			(at -0.899922 0.750062 270)
			(size 0.6096 0.6096)
			(layers "F.Cu" "F.Mask" "F.Paste")
			(net "PWRGD_P12V_SSD3_D")
		)
		(pad "4" smd rect
			(at 0.899922 0.750062 270)
			(size 0.6096 0.6096)
			(layers "F.Cu" "F.Mask" "F.Paste")
			(net "GND")
		)
		(pad "5" smd rect
			(at 0.899922 0 270)
			(size 0.4064 0.6096)
			(layers "F.Cu" "F.Mask" "F.Paste")
			(net "P12V_SSD3_PG_G2")
		)
		(pad "6" smd rect
			(at 0.899922 -0.750062 270)
			(size 0.6096 0.6096)
			(layers "F.Cu" "F.Mask" "F.Paste")
			(net "P12V_SSD3_PG_G2")
		)
	)
	(footprint ""
		(layer "F.Cu")
		(at 171.457874 -27.006296 -90)
		(property "Reference" "PR7111"
			(at 0 0 270)
			(layer "F.SilkS")
			(hide yes)
			(effects
				(font
					(size 1.27 1.27)
				)
			)
		)
		(property "Value" ""
			(at 0 0 270)
			(layer "F.Fab")
			(effects
				(font
					(size 1.27 1.27)
				)
			)
		)
		(duplicate_pad_numbers_are_jumpers no)
		(fp_line
			(start -0.7874 0.4064)
			(end -0.7874 -0.4064)
			(stroke
				(width 0.1524)
				(type default)
			)
			(layer "F.SilkS")
		)
		(fp_line
			(start 0.7874 0.4064)
			(end -0.7874 0.4064)
			(stroke
				(width 0.1524)
				(type default)
			)
			(layer "F.SilkS")
		)
		(fp_line
			(start -0.7874 -0.4064)
			(end 0.7874 -0.4064)
			(stroke
				(width 0.1524)
				(type default)
			)
			(layer "F.SilkS")
		)
		(fp_line
			(start 0.7874 -0.4064)
			(end 0.7874 0.4064)
			(stroke
				(width 0.1524)
				(type default)
			)
			(layer "F.SilkS")
		)
		(fp_line
			(start -0.67945 0.3048)
			(end -0.67945 -0.305054)
			(stroke
				(width 0.1)
				(type default)
			)
			(layer "F.Fab")
		)
		(fp_line
			(start -0.12065 0.3048)
			(end -0.67945 0.3048)
			(stroke
				(width 0.1)
				(type default)
			)
			(layer "F.Fab")
		)
		(fp_line
			(start 0.120396 0.3048)
			(end 0.120396 0.2794)
			(stroke
				(width 0.1)
				(type default)
			)
			(layer "F.Fab")
		)
		(fp_line
			(start 0.67945 0.3048)
			(end 0.120396 0.3048)
			(stroke
				(width 0.1)
				(type default)
			)
			(layer "F.Fab")
		)
		(fp_line
			(start -0.12065 0.2794)
			(end -0.12065 0.3048)
			(stroke
				(width 0.1)
				(type default)
			)
			(layer "F.Fab")
		)
		(fp_line
			(start 0.120396 0.2794)
			(end -0.12065 0.2794)
			(stroke
				(width 0.1)
				(type default)
			)
			(layer "F.Fab")
		)
		(fp_line
			(start -0.12065 -0.2794)
			(end 0.12065 -0.2794)
			(stroke
				(width 0.1)
				(type default)
			)
			(layer "F.Fab")
		)
		(fp_line
			(start 0.12065 -0.2794)
			(end 0.12065 -0.3048)
			(stroke
				(width 0.1)
				(type default)
			)
			(layer "F.Fab")
		)
		(fp_line
			(start 0.12065 -0.3048)
			(end 0.67945 -0.3048)
			(stroke
				(width 0.1)
				(type default)
			)
			(layer "F.Fab")
		)
		(fp_line
			(start 0.67945 -0.3048)
			(end 0.67945 0.3048)
			(stroke
				(width 0.1)
				(type default)
			)
			(layer "F.Fab")
		)
		(fp_line
			(start -0.67945 -0.305054)
			(end -0.12065 -0.305054)
			(stroke
				(width 0.1)
				(type default)
			)
			(layer "F.Fab")
		)
		(fp_line
			(start -0.12065 -0.305054)
			(end -0.12065 -0.2794)
			(stroke
				(width 0.1)
				(type default)
			)
			(layer "F.Fab")
		)
		(pad "1" smd circle
			(at -0.40005 0 270)
			(size 0 0)
			(layers "F.Cu" "F.Mask" "F.Paste")
			(net "P3V3_SSD6_CO_MODE")
		)
		(pad "2" smd circle
			(at 0.40005 0 270)
			(size 0 0)
			(layers "F.Cu" "F.Mask" "F.Paste")
			(net "GND")
		)
	)
	(footprint ""
		(layer "F.Cu")
		(at 144.956276 -32.848042 -90)
		(property "Reference" "R6055"
			(at 0 0 270)
			(layer "F.SilkS")
			(hide yes)
			(effects
				(font
					(size 1.27 1.27)
				)
			)
		)
		(property "Value" ""
			(at 0 0 270)
			(layer "F.Fab")
			(effects
				(font
					(size 1.27 1.27)
				)
			)
		)
		(duplicate_pad_numbers_are_jumpers no)
		(fp_line
			(start -0.7874 0.4064)
			(end -0.7874 -0.4064)
			(stroke
				(width 0.1524)
				(type default)
			)
			(layer "F.SilkS")
		)
		(fp_line
			(start 0.7874 0.4064)
			(end -0.7874 0.4064)
			(stroke
				(width 0.1524)
				(type default)
			)
			(layer "F.SilkS")
		)
		(fp_line
			(start -0.7874 -0.4064)
			(end 0.7874 -0.4064)
			(stroke
				(width 0.1524)
				(type default)
			)
			(layer "F.SilkS")
		)
		(fp_line
			(start 0.7874 -0.4064)
			(end 0.7874 0.4064)
			(stroke
				(width 0.1524)
				(type default)
			)
			(layer "F.SilkS")
		)
		(fp_line
			(start -0.67945 0.3048)
			(end -0.67945 -0.305054)
			(stroke
				(width 0.1)
				(type default)
			)
			(layer "F.Fab")
		)
		(fp_line
			(start -0.12065 0.3048)
			(end -0.67945 0.3048)
			(stroke
				(width 0.1)
				(type default)
			)
			(layer "F.Fab")
		)
		(fp_line
			(start 0.120396 0.3048)
			(end 0.120396 0.2794)
			(stroke
				(width 0.1)
				(type default)
			)
			(layer "F.Fab")
		)
		(fp_line
			(start 0.67945 0.3048)
			(end 0.120396 0.3048)
			(stroke
				(width 0.1)
				(type default)
			)
			(layer "F.Fab")
		)
		(fp_line
			(start -0.12065 0.2794)
			(end -0.12065 0.3048)
			(stroke
				(width 0.1)
				(type default)
			)
			(layer "F.Fab")
		)
		(fp_line
			(start 0.120396 0.2794)
			(end -0.12065 0.2794)
			(stroke
				(width 0.1)
				(type default)
			)
			(layer "F.Fab")
		)
		(fp_line
			(start -0.12065 -0.2794)
			(end 0.12065 -0.2794)
			(stroke
				(width 0.1)
				(type default)
			)
			(layer "F.Fab")
		)
		(fp_line
			(start 0.12065 -0.2794)
			(end 0.12065 -0.3048)
			(stroke
				(width 0.1)
				(type default)
			)
			(layer "F.Fab")
		)
		(fp_line
			(start 0.12065 -0.3048)
			(end 0.67945 -0.3048)
			(stroke
				(width 0.1)
				(type default)
			)
			(layer "F.Fab")
		)
		(fp_line
			(start 0.67945 -0.3048)
			(end 0.67945 0.3048)
			(stroke
				(width 0.1)
				(type default)
			)
			(layer "F.Fab")
		)
		(fp_line
			(start -0.67945 -0.305054)
			(end -0.12065 -0.305054)
			(stroke
				(width 0.1)
				(type default)
			)
			(layer "F.Fab")
		)
		(fp_line
			(start -0.12065 -0.305054)
			(end -0.12065 -0.2794)
			(stroke
				(width 0.1)
				(type default)
			)
			(layer "F.Fab")
		)
		(pad "1" smd circle
			(at -0.40005 0 270)
			(size 0 0)
			(layers "F.Cu" "F.Mask" "F.Paste")
			(net "SSD5_AUX_P3V3_EN_R")
		)
		(pad "2" smd circle
			(at 0.40005 0 270)
			(size 0 0)
			(layers "F.Cu" "F.Mask" "F.Paste")
			(net "P3V3_SSD5_CO_EN")
		)
	)
	(footprint ""
		(layer "F.Cu")
		(at 252.374908 -48.753014 180)
		(property "Reference" "C321"
			(at 0 0 180)
			(layer "F.SilkS")
			(hide yes)
			(effects
				(font
					(size 1.27 1.27)
				)
			)
		)
		(property "Value" ""
			(at 0 0 180)
			(layer "F.Fab")
			(effects
				(font
					(size 1.27 1.27)
				)
			)
		)
		(duplicate_pad_numbers_are_jumpers no)
		(fp_line
			(start 0.7874 0.4064)
			(end -0.7874 0.4064)
			(stroke
				(width 0.1524)
				(type default)
			)
			(layer "F.SilkS")
		)
		(fp_line
			(start 0.7874 -0.4064)
			(end 0.7874 0.4064)
			(stroke
				(width 0.1524)
				(type default)
			)
			(layer "F.SilkS")
		)
		(fp_line
			(start -0.7874 0.4064)
			(end -0.7874 -0.4064)
			(stroke
				(width 0.1524)
				(type default)
			)
			(layer "F.SilkS")
		)
		(fp_line
			(start -0.7874 -0.4064)
			(end 0.7874 -0.4064)
			(stroke
				(width 0.1524)
				(type default)
			)
			(layer "F.SilkS")
		)
		(fp_line
			(start 0.67945 0.3048)
			(end 0.120396 0.3048)
			(stroke
				(width 0.1)
				(type default)
			)
			(layer "F.Fab")
		)
		(fp_line
			(start 0.67945 -0.3048)
			(end 0.67945 0.3048)
			(stroke
				(width 0.1)
				(type default)
			)
			(layer "F.Fab")
		)
		(fp_line
			(start 0.12065 -0.2794)
			(end 0.12065 -0.3048)
			(stroke
				(width 0.1)
				(type default)
			)
			(layer "F.Fab")
		)
		(fp_line
			(start 0.12065 -0.3048)
			(end 0.67945 -0.3048)
			(stroke
				(width 0.1)
				(type default)
			)
			(layer "F.Fab")
		)
		(fp_line
			(start 0.120396 0.3048)
			(end 0.120396 0.2794)
			(stroke
				(width 0.1)
				(type default)
			)
			(layer "F.Fab")
		)
		(fp_line
			(start 0.120396 0.2794)
			(end -0.12065 0.2794)
			(stroke
				(width 0.1)
				(type default)
			)
			(layer "F.Fab")
		)
		(fp_line
			(start -0.12065 0.3048)
			(end -0.67945 0.3048)
			(stroke
				(width 0.1)
				(type default)
			)
			(layer "F.Fab")
		)
		(fp_line
			(start -0.12065 0.2794)
			(end -0.12065 0.3048)
			(stroke
				(width 0.1)
				(type default)
			)
			(layer "F.Fab")
		)
		(fp_line
			(start -0.12065 -0.2794)
			(end 0.12065 -0.2794)
			(stroke
				(width 0.1)
				(type default)
			)
			(layer "F.Fab")
		)
		(fp_line
			(start -0.12065 -0.305054)
			(end -0.12065 -0.2794)
			(stroke
				(width 0.1)
				(type default)
			)
			(layer "F.Fab")
		)
		(fp_line
			(start -0.67945 0.3048)
			(end -0.67945 -0.305054)
			(stroke
				(width 0.1)
				(type default)
			)
			(layer "F.Fab")
		)
		(fp_line
			(start -0.67945 -0.305054)
			(end -0.12065 -0.305054)
			(stroke
				(width 0.1)
				(type default)
			)
			(layer "F.Fab")
		)
		(pad "1" smd circle
			(at -0.40005 0 180)
			(size 0 0)
			(layers "F.Cu" "F.Mask" "F.Paste")
			(net "P3V3_AUX")
		)
		(pad "2" smd circle
			(at 0.40005 0 180)
			(size 0 0)
			(layers "F.Cu" "F.Mask" "F.Paste")
			(net "GND")
		)
	)
	(footprint ""
		(layer "F.Cu")
		(at 82.373724 -27.006296 -90)
		(property "Reference" "PC686"
			(at 0 0 270)
			(layer "F.SilkS")
			(hide yes)
			(effects
				(font
					(size 1.27 1.27)
				)
			)
		)
		(property "Value" ""
			(at 0 0 270)
			(layer "F.Fab")
			(effects
				(font
					(size 1.27 1.27)
				)
			)
		)
		(duplicate_pad_numbers_are_jumpers no)
		(fp_line
			(start -0.7874 0.4064)
			(end -0.7874 -0.4064)
			(stroke
				(width 0.1524)
				(type default)
			)
			(layer "F.SilkS")
		)
		(fp_line
			(start 0.7874 0.4064)
			(end -0.7874 0.4064)
			(stroke
				(width 0.1524)
				(type default)
			)
			(layer "F.SilkS")
		)
		(fp_line
			(start -0.7874 -0.4064)
			(end 0.7874 -0.4064)
			(stroke
				(width 0.1524)
				(type default)
			)
			(layer "F.SilkS")
		)
		(fp_line
			(start 0.7874 -0.4064)
			(end 0.7874 0.4064)
			(stroke
				(width 0.1524)
				(type default)
			)
			(layer "F.SilkS")
		)
		(fp_line
			(start -0.67945 0.3048)
			(end -0.67945 -0.305054)
			(stroke
				(width 0.1)
				(type default)
			)
			(layer "F.Fab")
		)
		(fp_line
			(start -0.12065 0.3048)
			(end -0.67945 0.3048)
			(stroke
				(width 0.1)
				(type default)
			)
			(layer "F.Fab")
		)
		(fp_line
			(start 0.120396 0.3048)
			(end 0.120396 0.2794)
			(stroke
				(width 0.1)
				(type default)
			)
			(layer "F.Fab")
		)
		(fp_line
			(start 0.67945 0.3048)
			(end 0.120396 0.3048)
			(stroke
				(width 0.1)
				(type default)
			)
			(layer "F.Fab")
		)
		(fp_line
			(start -0.12065 0.2794)
			(end -0.12065 0.3048)
			(stroke
				(width 0.1)
				(type default)
			)
			(layer "F.Fab")
		)
		(fp_line
			(start 0.120396 0.2794)
			(end -0.12065 0.2794)
			(stroke
				(width 0.1)
				(type default)
			)
			(layer "F.Fab")
		)
		(fp_line
			(start -0.12065 -0.2794)
			(end 0.12065 -0.2794)
			(stroke
				(width 0.1)
				(type default)
			)
			(layer "F.Fab")
		)
		(fp_line
			(start 0.12065 -0.2794)
			(end 0.12065 -0.3048)
			(stroke
				(width 0.1)
				(type default)
			)
			(layer "F.Fab")
		)
		(fp_line
			(start 0.12065 -0.3048)
			(end 0.67945 -0.3048)
			(stroke
				(width 0.1)
				(type default)
			)
			(layer "F.Fab")
		)
		(fp_line
			(start 0.67945 -0.3048)
			(end 0.67945 0.3048)
			(stroke
				(width 0.1)
				(type default)
			)
			(layer "F.Fab")
		)
		(fp_line
			(start -0.67945 -0.305054)
			(end -0.12065 -0.305054)
			(stroke
				(width 0.1)
				(type default)
			)
			(layer "F.Fab")
		)
		(fp_line
			(start -0.12065 -0.305054)
			(end -0.12065 -0.2794)
			(stroke
				(width 0.1)
				(type default)
			)
			(layer "F.Fab")
		)
		(pad "1" smd circle
			(at -0.40005 0 270)
			(size 0 0)
			(layers "F.Cu" "F.Mask" "F.Paste")
			(net "P3V3_SSD3_CO_MODE")
		)
		(pad "2" smd circle
			(at 0.40005 0 270)
			(size 0 0)
			(layers "F.Cu" "F.Mask" "F.Paste")
			(net "GND")
		)
	)
)
